(kicad_pcb
	(version 20260206)
	(generator "pcbnew")
	(generator_version "10.0")
	(general
		(thickness 1.6)
		(legacy_teardrops no)
	)
	(paper "A4")
	(title_block
		(title "12092022_DA0F0TFB6D0_F0T_FAN_BOARD_MP5048_D_brd_v02_OCP.brd")
		(comment 1 "Grand Teton / footprints 256-261 of 924")
	)
	(layers
		(0 "F.Cu" signal "TOP")
		(4 "In1.Cu" signal "GND")
		(6 "In2.Cu" signal "IN1")
		(8 "In3.Cu" signal "IN2")
		(10 "In4.Cu" signal "GND1")
		(2 "B.Cu" signal "BOTTOM")
		(9 "F.Adhes" user "F.Adhesive")
		(11 "B.Adhes" user "B.Adhesive")
		(13 "F.Paste" user "Package Geometry/Pastemask Top")
		(15 "B.Paste" user "Package Geometry/Pastemask Bottom")
		(5 "F.SilkS" user "Ref Des/Silkscreen Top")
		(7 "B.SilkS" user "Ref Des/Silkscreen Bottom")
		(1 "F.Mask" user "Board Geometry/Soldermask Top")
		(3 "B.Mask" user "Board Geometry/Soldermask Bottom")
		(17 "Dwgs.User" user "User.Drawings")
		(19 "Cmts.User" user "User.Comments")
		(21 "Eco1.User" user "User.Eco1")
		(23 "Eco2.User" user "User.Eco2")
		(25 "Edge.Cuts" user "Board Geometry/Outline")
		(27 "Margin" user)
		(31 "F.CrtYd" user "Package Geometry/Place Bound Top")
		(29 "B.CrtYd" user "Package Geometry/Place Bound Bottom")
		(35 "F.Fab" user "Ref Des/Assembly Top")
		(33 "B.Fab" user "Ref Des/Assembly Bottom")
	)
	(footprint ""
		(layer "F.Cu")
		(at 43.561 -172.847)
		(property "Reference" "R5097"
			(at 0 0 0)
			(layer "F.SilkS")
			(hide yes)
			(effects
				(font
					(size 1.27 1.27)
				)
			)
		)
		(property "Value" ""
			(at 0 0 0)
			(layer "F.Fab")
			(effects
				(font
					(size 1.27 1.27)
				)
			)
		)
		(duplicate_pad_numbers_are_jumpers no)
		(fp_line
			(start -0.7874 -0.4064)
			(end 0.7874 -0.4064)
			(stroke
				(width 0.1524)
				(type default)
			)
			(layer "F.SilkS")
		)
		(fp_line
			(start -0.7874 0.4064)
			(end -0.7874 -0.4064)
			(stroke
				(width 0.1524)
				(type default)
			)
			(layer "F.SilkS")
		)
		(fp_line
			(start 0.7874 -0.4064)
			(end 0.7874 0.4064)
			(stroke
				(width 0.1524)
				(type default)
			)
			(layer "F.SilkS")
		)
		(fp_line
			(start 0.7874 0.4064)
			(end -0.7874 0.4064)
			(stroke
				(width 0.1524)
				(type default)
			)
			(layer "F.SilkS")
		)
		(fp_line
			(start -0.67945 -0.305054)
			(end -0.12065 -0.305054)
			(stroke
				(width 0.1)
				(type default)
			)
			(layer "F.Fab")
		)
		(fp_line
			(start -0.67945 0.3048)
			(end -0.67945 -0.305054)
			(stroke
				(width 0.1)
				(type default)
			)
			(layer "F.Fab")
		)
		(fp_line
			(start -0.12065 -0.305054)
			(end -0.12065 -0.2794)
			(stroke
				(width 0.1)
				(type default)
			)
			(layer "F.Fab")
		)
		(fp_line
			(start -0.12065 -0.2794)
			(end 0.12065 -0.2794)
			(stroke
				(width 0.1)
				(type default)
			)
			(layer "F.Fab")
		)
		(fp_line
			(start -0.12065 0.2794)
			(end -0.12065 0.3048)
			(stroke
				(width 0.1)
				(type default)
			)
			(layer "F.Fab")
		)
		(fp_line
			(start -0.12065 0.3048)
			(end -0.67945 0.3048)
			(stroke
				(width 0.1)
				(type default)
			)
			(layer "F.Fab")
		)
		(fp_line
			(start 0.120396 0.2794)
			(end -0.12065 0.2794)
			(stroke
				(width 0.1)
				(type default)
			)
			(layer "F.Fab")
		)
		(fp_line
			(start 0.120396 0.3048)
			(end 0.120396 0.2794)
			(stroke
				(width 0.1)
				(type default)
			)
			(layer "F.Fab")
		)
		(fp_line
			(start 0.12065 -0.3048)
			(end 0.67945 -0.3048)
			(stroke
				(width 0.1)
				(type default)
			)
			(layer "F.Fab")
		)
		(fp_line
			(start 0.12065 -0.2794)
			(end 0.12065 -0.3048)
			(stroke
				(width 0.1)
				(type default)
			)
			(layer "F.Fab")
		)
		(fp_line
			(start 0.67945 -0.3048)
			(end 0.67945 0.3048)
			(stroke
				(width 0.1)
				(type default)
			)
			(layer "F.Fab")
		)
		(fp_line
			(start 0.67945 0.3048)
			(end 0.120396 0.3048)
			(stroke
				(width 0.1)
				(type default)
			)
			(layer "F.Fab")
		)
		(pad "1" smd circle
			(at -0.40005 0)
			(size 0 0)
			(layers "F.Cu" "F.Mask" "F.Paste")
			(net "FAN_1_FAIL_LED")
		)
		(pad "2" smd circle
			(at 0.40005 0)
			(size 0 0)
			(layers "F.Cu" "F.Mask" "F.Paste")
			(net "FAN_1_FAIL_R_LED")
		)
	)
	(footprint ""
		(layer "F.Cu")
		(at 8.763 -313.817)
		(property "Reference" "R5661"
			(at 0 0 0)
			(layer "F.SilkS")
			(hide yes)
			(effects
				(font
					(size 1.27 1.27)
				)
			)
		)
		(property "Value" ""
			(at 0 0 0)
			(layer "F.Fab")
			(effects
				(font
					(size 1.27 1.27)
				)
			)
		)
		(duplicate_pad_numbers_are_jumpers no)
		(fp_line
			(start -0.7874 -0.4064)
			(end 0.7874 -0.4064)
			(stroke
				(width 0.1524)
				(type default)
			)
			(layer "F.SilkS")
		)
		(fp_line
			(start -0.7874 0.4064)
			(end -0.7874 -0.4064)
			(stroke
				(width 0.1524)
				(type default)
			)
			(layer "F.SilkS")
		)
		(fp_line
			(start 0.7874 -0.4064)
			(end 0.7874 0.4064)
			(stroke
				(width 0.1524)
				(type default)
			)
			(layer "F.SilkS")
		)
		(fp_line
			(start 0.7874 0.4064)
			(end -0.7874 0.4064)
			(stroke
				(width 0.1524)
				(type default)
			)
			(layer "F.SilkS")
		)
		(fp_line
			(start -0.67945 -0.305054)
			(end -0.12065 -0.305054)
			(stroke
				(width 0.1)
				(type default)
			)
			(layer "F.Fab")
		)
		(fp_line
			(start -0.67945 0.3048)
			(end -0.67945 -0.305054)
			(stroke
				(width 0.1)
				(type default)
			)
			(layer "F.Fab")
		)
		(fp_line
			(start -0.12065 -0.305054)
			(end -0.12065 -0.2794)
			(stroke
				(width 0.1)
				(type default)
			)
			(layer "F.Fab")
		)
		(fp_line
			(start -0.12065 -0.2794)
			(end 0.12065 -0.2794)
			(stroke
				(width 0.1)
				(type default)
			)
			(layer "F.Fab")
		)
		(fp_line
			(start -0.12065 0.2794)
			(end -0.12065 0.3048)
			(stroke
				(width 0.1)
				(type default)
			)
			(layer "F.Fab")
		)
		(fp_line
			(start -0.12065 0.3048)
			(end -0.67945 0.3048)
			(stroke
				(width 0.1)
				(type default)
			)
			(layer "F.Fab")
		)
		(fp_line
			(start 0.120396 0.2794)
			(end -0.12065 0.2794)
			(stroke
				(width 0.1)
				(type default)
			)
			(layer "F.Fab")
		)
		(fp_line
			(start 0.120396 0.3048)
			(end 0.120396 0.2794)
			(stroke
				(width 0.1)
				(type default)
			)
			(layer "F.Fab")
		)
		(fp_line
			(start 0.12065 -0.3048)
			(end 0.67945 -0.3048)
			(stroke
				(width 0.1)
				(type default)
			)
			(layer "F.Fab")
		)
		(fp_line
			(start 0.12065 -0.2794)
			(end 0.12065 -0.3048)
			(stroke
				(width 0.1)
				(type default)
			)
			(layer "F.Fab")
		)
		(fp_line
			(start 0.67945 -0.3048)
			(end 0.67945 0.3048)
			(stroke
				(width 0.1)
				(type default)
			)
			(layer "F.Fab")
		)
		(fp_line
			(start 0.67945 0.3048)
			(end 0.120396 0.3048)
			(stroke
				(width 0.1)
				(type default)
			)
			(layer "F.Fab")
		)
		(pad "1" smd rect
			(at -0.40005 0 180)
			(size 0.4572 0.508)
			(layers "F.Cu" "F.Mask" "F.Paste")
			(net "P12V_LED")
		)
		(pad "2" smd rect
			(at 0.40005 0 180)
			(size 0.4572 0.508)
			(layers "F.Cu" "F.Mask" "F.Paste")
			(net "U412_D1")
		)
	)
	(footprint ""
		(layer "F.Cu")
		(at 28.956 -168.529)
		(property "Reference" "R5468"
			(at 0 0 0)
			(layer "F.SilkS")
			(hide yes)
			(effects
				(font
					(size 1.27 1.27)
				)
			)
		)
		(property "Value" ""
			(at 0 0 0)
			(layer "F.Fab")
			(effects
				(font
					(size 1.27 1.27)
				)
			)
		)
		(duplicate_pad_numbers_are_jumpers no)
		(fp_line
			(start -0.7874 -0.4064)
			(end 0.7874 -0.4064)
			(stroke
				(width 0.1524)
				(type default)
			)
			(layer "F.SilkS")
		)
		(fp_line
			(start -0.7874 0.4064)
			(end -0.7874 -0.4064)
			(stroke
				(width 0.1524)
				(type default)
			)
			(layer "F.SilkS")
		)
		(fp_line
			(start 0.7874 -0.4064)
			(end 0.7874 0.4064)
			(stroke
				(width 0.1524)
				(type default)
			)
			(layer "F.SilkS")
		)
		(fp_line
			(start 0.7874 0.4064)
			(end -0.7874 0.4064)
			(stroke
				(width 0.1524)
				(type default)
			)
			(layer "F.SilkS")
		)
		(fp_line
			(start -0.67945 -0.305054)
			(end -0.12065 -0.305054)
			(stroke
				(width 0.1)
				(type default)
			)
			(layer "F.Fab")
		)
		(fp_line
			(start -0.67945 0.3048)
			(end -0.67945 -0.305054)
			(stroke
				(width 0.1)
				(type default)
			)
			(layer "F.Fab")
		)
		(fp_line
			(start -0.12065 -0.305054)
			(end -0.12065 -0.2794)
			(stroke
				(width 0.1)
				(type default)
			)
			(layer "F.Fab")
		)
		(fp_line
			(start -0.12065 -0.2794)
			(end 0.12065 -0.2794)
			(stroke
				(width 0.1)
				(type default)
			)
			(layer "F.Fab")
		)
		(fp_line
			(start -0.12065 0.2794)
			(end -0.12065 0.3048)
			(stroke
				(width 0.1)
				(type default)
			)
			(layer "F.Fab")
		)
		(fp_line
			(start -0.12065 0.3048)
			(end -0.67945 0.3048)
			(stroke
				(width 0.1)
				(type default)
			)
			(layer "F.Fab")
		)
		(fp_line
			(start 0.120396 0.2794)
			(end -0.12065 0.2794)
			(stroke
				(width 0.1)
				(type default)
			)
			(layer "F.Fab")
		)
		(fp_line
			(start 0.120396 0.3048)
			(end 0.120396 0.2794)
			(stroke
				(width 0.1)
				(type default)
			)
			(layer "F.Fab")
		)
		(fp_line
			(start 0.12065 -0.3048)
			(end 0.67945 -0.3048)
			(stroke
				(width 0.1)
				(type default)
			)
			(layer "F.Fab")
		)
		(fp_line
			(start 0.12065 -0.2794)
			(end 0.12065 -0.3048)
			(stroke
				(width 0.1)
				(type default)
			)
			(layer "F.Fab")
		)
		(fp_line
			(start 0.67945 -0.3048)
			(end 0.67945 0.3048)
			(stroke
				(width 0.1)
				(type default)
			)
			(layer "F.Fab")
		)
		(fp_line
			(start 0.67945 0.3048)
			(end 0.120396 0.3048)
			(stroke
				(width 0.1)
				(type default)
			)
			(layer "F.Fab")
		)
		(pad "1" smd circle
			(at -0.40005 0)
			(size 0 0)
			(layers "F.Cu" "F.Mask" "F.Paste")
			(net "SMB_PDBV_FAN_SCL")
		)
		(pad "2" smd circle
			(at 0.40005 0)
			(size 0 0)
			(layers "F.Cu" "F.Mask" "F.Paste")
			(net "SMB_PDBV_FAN_R1_IOX_SCL")
		)
	)
	(footprint ""
		(layer "F.Cu")
		(at 20.828 -172.72)
		(property "Reference" "R5674"
			(at 0 0 0)
			(layer "F.SilkS")
			(hide yes)
			(effects
				(font
					(size 1.27 1.27)
				)
			)
		)
		(property "Value" ""
			(at 0 0 0)
			(layer "F.Fab")
			(effects
				(font
					(size 1.27 1.27)
				)
			)
		)
		(duplicate_pad_numbers_are_jumpers no)
		(fp_line
			(start -0.7874 -0.4064)
			(end 0.7874 -0.4064)
			(stroke
				(width 0.1524)
				(type default)
			)
			(layer "F.SilkS")
		)
		(fp_line
			(start -0.7874 0.4064)
			(end -0.7874 -0.4064)
			(stroke
				(width 0.1524)
				(type default)
			)
			(layer "F.SilkS")
		)
		(fp_line
			(start 0.7874 -0.4064)
			(end 0.7874 0.4064)
			(stroke
				(width 0.1524)
				(type default)
			)
			(layer "F.SilkS")
		)
		(fp_line
			(start 0.7874 0.4064)
			(end -0.7874 0.4064)
			(stroke
				(width 0.1524)
				(type default)
			)
			(layer "F.SilkS")
		)
		(fp_line
			(start -0.67945 -0.305054)
			(end -0.12065 -0.305054)
			(stroke
				(width 0.1)
				(type default)
			)
			(layer "F.Fab")
		)
		(fp_line
			(start -0.67945 0.3048)
			(end -0.67945 -0.305054)
			(stroke
				(width 0.1)
				(type default)
			)
			(layer "F.Fab")
		)
		(fp_line
			(start -0.12065 -0.305054)
			(end -0.12065 -0.2794)
			(stroke
				(width 0.1)
				(type default)
			)
			(layer "F.Fab")
		)
		(fp_line
			(start -0.12065 -0.2794)
			(end 0.12065 -0.2794)
			(stroke
				(width 0.1)
				(type default)
			)
			(layer "F.Fab")
		)
		(fp_line
			(start -0.12065 0.2794)
			(end -0.12065 0.3048)
			(stroke
				(width 0.1)
				(type default)
			)
			(layer "F.Fab")
		)
		(fp_line
			(start -0.12065 0.3048)
			(end -0.67945 0.3048)
			(stroke
				(width 0.1)
				(type default)
			)
			(layer "F.Fab")
		)
		(fp_line
			(start 0.120396 0.2794)
			(end -0.12065 0.2794)
			(stroke
				(width 0.1)
				(type default)
			)
			(layer "F.Fab")
		)
		(fp_line
			(start 0.120396 0.3048)
			(end 0.120396 0.2794)
			(stroke
				(width 0.1)
				(type default)
			)
			(layer "F.Fab")
		)
		(fp_line
			(start 0.12065 -0.3048)
			(end 0.67945 -0.3048)
			(stroke
				(width 0.1)
				(type default)
			)
			(layer "F.Fab")
		)
		(fp_line
			(start 0.12065 -0.2794)
			(end 0.12065 -0.3048)
			(stroke
				(width 0.1)
				(type default)
			)
			(layer "F.Fab")
		)
		(fp_line
			(start 0.67945 -0.3048)
			(end 0.67945 0.3048)
			(stroke
				(width 0.1)
				(type default)
			)
			(layer "F.Fab")
		)
		(fp_line
			(start 0.67945 0.3048)
			(end 0.120396 0.3048)
			(stroke
				(width 0.1)
				(type default)
			)
			(layer "F.Fab")
		)
		(pad "1" smd circle
			(at -0.40005 0)
			(size 0 0)
			(layers "F.Cu" "F.Mask" "F.Paste")
			(net "FM_BOARD_SKU_ID1")
		)
		(pad "2" smd circle
			(at 0.40005 0)
			(size 0 0)
			(layers "F.Cu" "F.Mask" "F.Paste")
			(net "GND")
		)
	)
	(footprint ""
		(layer "F.Cu")
		(at 33.02 -299.339)
		(property "Reference" "D268"
			(at -0.508 1.16967 0)
			(unlocked yes)
			(layer "F.SilkS")
			(effects
				(font
					(size 0.7874 0.5842)
					(thickness 0.1524)
				)
				(justify left)
			)
		)
		(property "Value" ""
			(at 0 0 0)
			(layer "F.Fab")
			(effects
				(font
					(size 1.27 1.27)
				)
			)
		)
		(duplicate_pad_numbers_are_jumpers no)
		(fp_line
			(start -0.854964 -0.450088)
			(end -0.854964 0.450088)
			(stroke
				(width 0.1524)
				(type default)
			)
			(layer "F.SilkS")
		)
		(fp_line
			(start -0.854964 0.450088)
			(end 0.925068 0.450088)
			(stroke
				(width 0.1524)
				(type default)
			)
			(layer "F.SilkS")
		)
		(fp_line
			(start 0.845058 0.4064)
			(end 0.845058 -0.381)
			(stroke
				(width 0.1524)
				(type default)
			)
			(layer "F.SilkS")
		)
		(fp_line
			(start 0.870458 -0.2794)
			(end 0.845058 0.4064)
			(stroke
				(width 0.1524)
				(type default)
			)
			(layer "F.SilkS")
		)
		(fp_line
			(start 0.94488 -0.450088)
			(end -0.854964 -0.450088)
			(stroke
				(width 0.1524)
				(type default)
			)
			(layer "F.SilkS")
		)
		(fp_line
			(start 0.94488 0.450088)
			(end 0.94488 -0.450088)
			(stroke
				(width 0.1524)
				(type default)
			)
			(layer "F.SilkS")
		)
		(fp_line
			(start -0.54991 -0.350012)
			(end -0.54991 0.350012)
			(stroke
				(width 0.1)
				(type default)
			)
			(layer "F.Fab")
		)
		(fp_line
			(start -0.54991 0.350012)
			(end 0.54991 0.350012)
			(stroke
				(width 0.1)
				(type default)
			)
			(layer "F.Fab")
		)
		(fp_line
			(start 0.54991 -0.350012)
			(end -0.54991 -0.350012)
			(stroke
				(width 0.1)
				(type default)
			)
			(layer "F.Fab")
		)
		(fp_line
			(start 0.54991 0.350012)
			(end 0.54991 -0.350012)
			(stroke
				(width 0.1)
				(type default)
			)
			(layer "F.Fab")
		)
		(fp_text user "+"
			(at -1.143 0.47625 180)
			(unlocked yes)
			(layer "F.SilkS")
			(effects
				(font
					(size 1.905 1.4224)
					(thickness 0.1524)
				)
				(justify left)
			)
		)
		(fp_text user "-"
			(at 1.778 -0.41275 180)
			(unlocked yes)
			(layer "F.SilkS")
			(effects
				(font
					(size 1.905 1.4224)
					(thickness 0.1524)
				)
				(justify left)
			)
		)
		(fp_text user "+"
			(at -0.808228 0.239014 180)
			(unlocked yes)
			(layer "F.Fab")
			(effects
				(font
					(size 1.905 1.4224)
					(thickness 0.1524)
				)
				(justify left)
			)
		)
		(fp_text user "-"
			(at 2.48539 0.239014 180)
			(unlocked yes)
			(layer "F.Fab")
			(effects
				(font
					(size 1.905 1.4224)
					(thickness 0.1524)
				)
				(justify left)
			)
		)
		(pad "A" smd rect
			(at -0.424942 0)
			(size 0.5588 0.6096)
			(layers "F.Cu" "F.Mask" "F.Paste")
			(net "GND")
		)
		(pad "C" smd rect
			(at 0.424942 0 180)
			(size 0.5588 0.6096)
			(layers "F.Cu" "F.Mask" "F.Paste")
			(net "FAN_0_PWM_IL_R")
		)
	)
	(footprint ""
		(layer "F.Cu")
		(at 29.083 -197.358 -90)
		(property "Reference" "U401"
			(at -1.905 1.24333 90)
			(unlocked yes)
			(layer "F.SilkS")
			(effects
				(font
					(size 0.7874 0.5842)
					(thickness 0.1524)
				)
				(justify left)
			)
		)
		(property "Value" ""
			(at 0 0 270)
			(layer "F.Fab")
			(effects
				(font
					(size 1.27 1.27)
				)
			)
		)
		(duplicate_pad_numbers_are_jumpers no)
		(fp_line
			(start -1.33096 1.100074)
			(end -1.33096 -1.100074)
			(stroke
				(width 0.1524)
				(type default)
			)
			(layer "F.SilkS")
		)
		(fp_line
			(start 1.33096 1.100074)
			(end -1.33096 1.100074)
			(stroke
				(width 0.1524)
				(type default)
			)
			(layer "F.SilkS")
		)
		(fp_line
			(start 0 -0.649986)
			(end 0.381 -1.100074)
			(stroke
				(width 0.1524)
				(type default)
			)
			(layer "F.SilkS")
		)
		(fp_line
			(start -1.33096 -1.100074)
			(end -0.381 -1.100074)
			(stroke
				(width 0.1524)
				(type default)
			)
			(layer "F.SilkS")
		)
		(fp_line
			(start -0.381 -1.100074)
			(end 0 -0.649986)
			(stroke
				(width 0.1524)
				(type default)
			)
			(layer "F.SilkS")
		)
		(fp_line
			(start 0.381 -1.100074)
			(end 1.33096 -1.100074)
			(stroke
				(width 0.1524)
				(type default)
			)
			(layer "F.SilkS")
		)
		(fp_line
			(start 1.33096 -1.100074)
			(end 1.33096 1.100074)
			(stroke
				(width 0.1524)
				(type default)
			)
			(layer "F.SilkS")
		)
		(fp_poly
			(pts
				(xy -2.209292 -1.029462) (xy -2.209292 -0.521462) (xy -1.447292 -0.775462)
			)
			(stroke
				(width 0)
				(type default)
			)
			(fill yes)
			(layer "F.SilkS")
		)
		(fp_line
			(start -0.674878 1.100074)
			(end -0.674878 -1.100074)
			(stroke
				(width 0.1)
				(type default)
			)
			(layer "F.Fab")
		)
		(fp_line
			(start 0.674878 1.100074)
			(end -0.674878 1.100074)
			(stroke
				(width 0.1)
				(type default)
			)
			(layer "F.Fab")
		)
		(fp_line
			(start -0.674878 -1.100074)
			(end 0.674878 -1.100074)
			(stroke
				(width 0.1)
				(type default)
			)
			(layer "F.Fab")
		)
		(fp_line
			(start 0.674878 -1.100074)
			(end 0.674878 1.100074)
			(stroke
				(width 0.1)
				(type default)
			)
			(layer "F.Fab")
		)
		(fp_poly
			(pts
				(xy -2.209292 -0.902462) (xy -2.209292 -0.394462) (xy -1.447292 -0.648462)
			)
			(stroke
				(width 0)
				(type default)
			)
			(fill yes)
			(layer "F.Fab")
		)
		(pad "1" smd rect
			(at -0.94996 -0.649986)
			(size 0.4064 0.508)
			(layers "F.Cu" "F.Mask" "F.Paste")
			(net "NC_U401_P1")
		)
		(pad "2" smd rect
			(at -0.94996 0)
			(size 0.4064 0.508)
			(layers "F.Cu" "F.Mask" "F.Paste")
			(net "FAN_6_PWM")
		)
		(pad "3" smd rect
			(at -0.94996 0.649986)
			(size 0.4064 0.508)
			(layers "F.Cu" "F.Mask" "F.Paste")
			(net "GND")
		)
		(pad "4" smd rect
			(at 0.94996 0.649986)
			(size 0.4064 0.508)
			(layers "F.Cu" "F.Mask" "F.Paste")
			(net "FAN_6_PWM_BUF")
		)
		(pad "5" smd rect
			(at 0.94996 -0.649986)
			(size 0.4064 0.508)
			(layers "F.Cu" "F.Mask" "F.Paste")
			(net "P3V3_AUX")
		)
	)
)
